(kicad_pcb
	(version 20260206)
	(generator "pcbnew")
	(generator_version "10.0")
	(general
		(thickness 1.6)
		(legacy_teardrops no)
	)
	(paper "A4")
	(title_block
		(title "03242023_DA0F0TMBIJ0_F0T_Motherboard_J_brd_V01_OCP.brd")
		(comment 1 "Grand Teton / footprints 434-441 of 6105")
	)
	(layers
		(0 "F.Cu" signal "TOP")
		(4 "In1.Cu" signal "GND")
		(6 "In2.Cu" signal "IN1")
		(8 "In3.Cu" signal "GND1")
		(10 "In4.Cu" signal "IN2")
		(12 "In5.Cu" signal "GND2")
		(14 "In6.Cu" signal "IN3")
		(16 "In7.Cu" signal "GND3")
		(18 "In8.Cu" signal "VCC")
		(20 "In9.Cu" signal "VCC1")
		(22 "In10.Cu" signal "GND4")
		(24 "In11.Cu" signal "IN4")
		(26 "In12.Cu" signal "GND5")
		(28 "In13.Cu" signal "IN5")
		(30 "In14.Cu" signal "GND6")
		(32 "In15.Cu" signal "IN6")
		(34 "In16.Cu" signal "GND7")
		(2 "B.Cu" signal "BOTTOM")
		(9 "F.Adhes" user "F.Adhesive")
		(11 "B.Adhes" user "B.Adhesive")
		(13 "F.Paste" user "Package Geometry/Pastemask Top")
		(15 "B.Paste" user "Package Geometry/Pastemask Bottom")
		(5 "F.SilkS" user "Ref Des/Silkscreen Top")
		(7 "B.SilkS" user "Ref Des/Silkscreen Bottom")
		(1 "F.Mask" user "Board Geometry/Soldermask Top")
		(3 "B.Mask" user "Board Geometry/Soldermask Bottom")
		(17 "Dwgs.User" user "User.Drawings")
		(19 "Cmts.User" user "User.Comments")
		(21 "Eco1.User" user "User.Eco1")
		(23 "Eco2.User" user "User.Eco2")
		(25 "Edge.Cuts" user "Board Geometry/Outline")
		(27 "Margin" user)
		(31 "F.CrtYd" user "Package Geometry/Place Bound Top")
		(29 "B.CrtYd" user "Package Geometry/Place Bound Bottom")
		(35 "F.Fab" user "Ref Des/Assembly Top")
		(33 "B.Fab" user "Ref Des/Assembly Bottom")
	)
	(footprint ""
		(layer "F.Cu")
		(at 420.453312 -366.658144)
		(property "Reference" "PC720_P0_1"
			(at 0 0 0)
			(layer "F.SilkS")
			(hide yes)
			(effects
				(font
					(size 1.27 1.27)
				)
			)
		)
		(property "Value" ""
			(at 0 0 0)
			(layer "F.Fab")
			(effects
				(font
					(size 1.27 1.27)
				)
			)
		)
		(duplicate_pad_numbers_are_jumpers no)
		(fp_line
			(start -1.524 -0.762)
			(end 1.524 -0.762)
			(stroke
				(width 0.1524)
				(type default)
			)
			(layer "F.SilkS")
		)
		(fp_line
			(start -1.524 0.762)
			(end -1.524 -0.762)
			(stroke
				(width 0.1524)
				(type default)
			)
			(layer "F.SilkS")
		)
		(fp_line
			(start 1.524 -0.762)
			(end 1.524 0.762)
			(stroke
				(width 0.1524)
				(type default)
			)
			(layer "F.SilkS")
		)
		(fp_line
			(start 1.524 0.762)
			(end -1.524 0.762)
			(stroke
				(width 0.1524)
				(type default)
			)
			(layer "F.SilkS")
		)
		(fp_line
			(start -1.1049 -0.724916)
			(end -1.1049 0.724916)
			(stroke
				(width 0.1)
				(type default)
			)
			(layer "F.Fab")
		)
		(fp_line
			(start -1.1049 0.724916)
			(end 1.1049 0.724916)
			(stroke
				(width 0.1)
				(type default)
			)
			(layer "F.Fab")
		)
		(fp_line
			(start 1.1049 -0.724916)
			(end -1.1049 -0.724916)
			(stroke
				(width 0.1)
				(type default)
			)
			(layer "F.Fab")
		)
		(fp_line
			(start 1.1049 0.724916)
			(end 1.1049 -0.724916)
			(stroke
				(width 0.1)
				(type default)
			)
			(layer "F.Fab")
		)
		(pad "1" smd rect
			(at -0.889 0 180)
			(size 1.016 1.27)
			(layers "F.Cu" "F.Mask" "F.Paste")
			(net "SW_P12V_PVCCFA_EHV_FIVRA_CPU0_R")
		)
		(pad "2" smd rect
			(at 0.889 0 180)
			(size 1.016 1.27)
			(layers "F.Cu" "F.Mask" "F.Paste")
			(net "GND")
		)
	)
	(footprint ""
		(layer "F.Cu")
		(at 148.13788 -56.225948)
		(property "Reference" "R1702"
			(at 0 0 0)
			(layer "F.SilkS")
			(hide yes)
			(effects
				(font
					(size 1.27 1.27)
				)
			)
		)
		(property "Value" ""
			(at 0 0 0)
			(layer "F.Fab")
			(effects
				(font
					(size 1.27 1.27)
				)
			)
		)
		(duplicate_pad_numbers_are_jumpers no)
		(fp_line
			(start -0.7874 -0.4064)
			(end 0.7874 -0.4064)
			(stroke
				(width 0.1524)
				(type default)
			)
			(layer "F.SilkS")
		)
		(fp_line
			(start -0.7874 0.4064)
			(end -0.7874 -0.4064)
			(stroke
				(width 0.1524)
				(type default)
			)
			(layer "F.SilkS")
		)
		(fp_line
			(start 0.7874 -0.4064)
			(end 0.7874 0.4064)
			(stroke
				(width 0.1524)
				(type default)
			)
			(layer "F.SilkS")
		)
		(fp_line
			(start 0.7874 0.4064)
			(end -0.7874 0.4064)
			(stroke
				(width 0.1524)
				(type default)
			)
			(layer "F.SilkS")
		)
		(fp_line
			(start -0.67945 -0.305054)
			(end -0.12065 -0.305054)
			(stroke
				(width 0.1)
				(type default)
			)
			(layer "F.Fab")
		)
		(fp_line
			(start -0.67945 0.3048)
			(end -0.67945 -0.305054)
			(stroke
				(width 0.1)
				(type default)
			)
			(layer "F.Fab")
		)
		(fp_line
			(start -0.12065 -0.305054)
			(end -0.12065 -0.2794)
			(stroke
				(width 0.1)
				(type default)
			)
			(layer "F.Fab")
		)
		(fp_line
			(start -0.12065 -0.2794)
			(end 0.12065 -0.2794)
			(stroke
				(width 0.1)
				(type default)
			)
			(layer "F.Fab")
		)
		(fp_line
			(start -0.12065 0.2794)
			(end -0.12065 0.3048)
			(stroke
				(width 0.1)
				(type default)
			)
			(layer "F.Fab")
		)
		(fp_line
			(start -0.12065 0.3048)
			(end -0.67945 0.3048)
			(stroke
				(width 0.1)
				(type default)
			)
			(layer "F.Fab")
		)
		(fp_line
			(start 0.120396 0.2794)
			(end -0.12065 0.2794)
			(stroke
				(width 0.1)
				(type default)
			)
			(layer "F.Fab")
		)
		(fp_line
			(start 0.120396 0.3048)
			(end 0.120396 0.2794)
			(stroke
				(width 0.1)
				(type default)
			)
			(layer "F.Fab")
		)
		(fp_line
			(start 0.12065 -0.3048)
			(end 0.67945 -0.3048)
			(stroke
				(width 0.1)
				(type default)
			)
			(layer "F.Fab")
		)
		(fp_line
			(start 0.12065 -0.2794)
			(end 0.12065 -0.3048)
			(stroke
				(width 0.1)
				(type default)
			)
			(layer "F.Fab")
		)
		(fp_line
			(start 0.67945 -0.3048)
			(end 0.67945 0.3048)
			(stroke
				(width 0.1)
				(type default)
			)
			(layer "F.Fab")
		)
		(fp_line
			(start 0.67945 0.3048)
			(end 0.120396 0.3048)
			(stroke
				(width 0.1)
				(type default)
			)
			(layer "F.Fab")
		)
		(pad "1" smd circle
			(at -0.40005 0)
			(size 0 0)
			(layers "F.Cu" "F.Mask" "F.Paste")
			(net "P1V8_PCH_AUX")
		)
		(pad "2" smd circle
			(at 0.40005 0)
			(size 0 0)
			(layers "F.Cu" "F.Mask" "F.Paste")
			(net "SMB_M2_P0_1V8AUX_SDA_R")
		)
	)
	(footprint ""
		(layer "F.Cu")
		(at 385.716272 -65.688464)
		(property "Reference" "R762"
			(at 0 0 0)
			(layer "F.SilkS")
			(hide yes)
			(effects
				(font
					(size 1.27 1.27)
				)
			)
		)
		(property "Value" ""
			(at 0 0 0)
			(layer "F.Fab")
			(effects
				(font
					(size 1.27 1.27)
				)
			)
		)
		(duplicate_pad_numbers_are_jumpers no)
		(fp_line
			(start -0.7874 -0.4064)
			(end 0.7874 -0.4064)
			(stroke
				(width 0.1524)
				(type default)
			)
			(layer "F.SilkS")
		)
		(fp_line
			(start -0.7874 0.4064)
			(end -0.7874 -0.4064)
			(stroke
				(width 0.1524)
				(type default)
			)
			(layer "F.SilkS")
		)
		(fp_line
			(start 0.7874 -0.4064)
			(end 0.7874 0.4064)
			(stroke
				(width 0.1524)
				(type default)
			)
			(layer "F.SilkS")
		)
		(fp_line
			(start 0.7874 0.4064)
			(end -0.7874 0.4064)
			(stroke
				(width 0.1524)
				(type default)
			)
			(layer "F.SilkS")
		)
		(fp_line
			(start -0.67945 -0.305054)
			(end -0.12065 -0.305054)
			(stroke
				(width 0.1)
				(type default)
			)
			(layer "F.Fab")
		)
		(fp_line
			(start -0.67945 0.3048)
			(end -0.67945 -0.305054)
			(stroke
				(width 0.1)
				(type default)
			)
			(layer "F.Fab")
		)
		(fp_line
			(start -0.12065 -0.305054)
			(end -0.12065 -0.2794)
			(stroke
				(width 0.1)
				(type default)
			)
			(layer "F.Fab")
		)
		(fp_line
			(start -0.12065 -0.2794)
			(end 0.12065 -0.2794)
			(stroke
				(width 0.1)
				(type default)
			)
			(layer "F.Fab")
		)
		(fp_line
			(start -0.12065 0.2794)
			(end -0.12065 0.3048)
			(stroke
				(width 0.1)
				(type default)
			)
			(layer "F.Fab")
		)
		(fp_line
			(start -0.12065 0.3048)
			(end -0.67945 0.3048)
			(stroke
				(width 0.1)
				(type default)
			)
			(layer "F.Fab")
		)
		(fp_line
			(start 0.120396 0.2794)
			(end -0.12065 0.2794)
			(stroke
				(width 0.1)
				(type default)
			)
			(layer "F.Fab")
		)
		(fp_line
			(start 0.120396 0.3048)
			(end 0.120396 0.2794)
			(stroke
				(width 0.1)
				(type default)
			)
			(layer "F.Fab")
		)
		(fp_line
			(start 0.12065 -0.3048)
			(end 0.67945 -0.3048)
			(stroke
				(width 0.1)
				(type default)
			)
			(layer "F.Fab")
		)
		(fp_line
			(start 0.12065 -0.2794)
			(end 0.12065 -0.3048)
			(stroke
				(width 0.1)
				(type default)
			)
			(layer "F.Fab")
		)
		(fp_line
			(start 0.67945 -0.3048)
			(end 0.67945 0.3048)
			(stroke
				(width 0.1)
				(type default)
			)
			(layer "F.Fab")
		)
		(fp_line
			(start 0.67945 0.3048)
			(end 0.120396 0.3048)
			(stroke
				(width 0.1)
				(type default)
			)
			(layer "F.Fab")
		)
		(pad "1" smd circle
			(at -0.40005 0)
			(size 0 0)
			(layers "F.Cu" "F.Mask" "F.Paste")
			(net "JTAG_DBP_CPU_GTL_TCK")
		)
		(pad "2" smd circle
			(at 0.40005 0)
			(size 0 0)
			(layers "F.Cu" "F.Mask" "F.Paste")
			(net "JTAG_DBP_CPU_GTL_TCK_R")
		)
	)
	(footprint ""
		(layer "F.Cu")
		(at 81.915 -353.52482)
		(property "Reference" "H47"
			(at -3.58394 -5.029708 0)
			(unlocked yes)
			(layer "F.SilkS")
			(effects
				(font
					(size 0.7874 0.5842)
					(thickness 0.1524)
				)
				(justify left)
			)
		)
		(property "Value" ""
			(at 0 0 0)
			(layer "F.Fab")
			(effects
				(font
					(size 1.27 1.27)
				)
			)
		)
		(duplicate_pad_numbers_are_jumpers no)
		(pad "1" thru_hole circle
			(at 0 0)
			(size 8.001 8.001)
			(drill 3.2004)
			(layers "*.Cu" "*.Mask")
			(remove_unused_layers no)
			(net "GND")
			(clearance -2.1463)
			(padstack
				(mode front_inner_back)
				(layer "Inner"
					(shape circle)
					(size 5.0038 5.0038)
					(clearance -0.6477)
				)
				(layer "B.Cu"
					(shape circle)
					(size 8.001 8.001)
					(clearance -2.1463)
				)
			)
		)
	)
	(footprint ""
		(layer "F.Cu")
		(at 107.287314 -260.36524 -90)
		(property "Reference" "C433"
			(at 0 0 270)
			(layer "F.SilkS")
			(hide yes)
			(effects
				(font
					(size 1.27 1.27)
				)
			)
		)
		(property "Value" ""
			(at 0 0 270)
			(layer "F.Fab")
			(effects
				(font
					(size 1.27 1.27)
				)
			)
		)
		(duplicate_pad_numbers_are_jumpers no)
		(fp_line
			(start -0.7874 0.4064)
			(end -0.7874 -0.4064)
			(stroke
				(width 0.1524)
				(type default)
			)
			(layer "F.SilkS")
		)
		(fp_line
			(start 0.7874 0.4064)
			(end -0.7874 0.4064)
			(stroke
				(width 0.1524)
				(type default)
			)
			(layer "F.SilkS")
		)
		(fp_line
			(start -0.7874 -0.4064)
			(end 0.7874 -0.4064)
			(stroke
				(width 0.1524)
				(type default)
			)
			(layer "F.SilkS")
		)
		(fp_line
			(start 0.7874 -0.4064)
			(end 0.7874 0.4064)
			(stroke
				(width 0.1524)
				(type default)
			)
			(layer "F.SilkS")
		)
		(fp_line
			(start -0.67945 0.3048)
			(end -0.67945 -0.305054)
			(stroke
				(width 0.1)
				(type default)
			)
			(layer "F.Fab")
		)
		(fp_line
			(start -0.12065 0.3048)
			(end -0.67945 0.3048)
			(stroke
				(width 0.1)
				(type default)
			)
			(layer "F.Fab")
		)
		(fp_line
			(start 0.120396 0.3048)
			(end 0.120396 0.2794)
			(stroke
				(width 0.1)
				(type default)
			)
			(layer "F.Fab")
		)
		(fp_line
			(start 0.67945 0.3048)
			(end 0.120396 0.3048)
			(stroke
				(width 0.1)
				(type default)
			)
			(layer "F.Fab")
		)
		(fp_line
			(start -0.12065 0.2794)
			(end -0.12065 0.3048)
			(stroke
				(width 0.1)
				(type default)
			)
			(layer "F.Fab")
		)
		(fp_line
			(start 0.120396 0.2794)
			(end -0.12065 0.2794)
			(stroke
				(width 0.1)
				(type default)
			)
			(layer "F.Fab")
		)
		(fp_line
			(start -0.12065 -0.2794)
			(end 0.12065 -0.2794)
			(stroke
				(width 0.1)
				(type default)
			)
			(layer "F.Fab")
		)
		(fp_line
			(start 0.12065 -0.2794)
			(end 0.12065 -0.3048)
			(stroke
				(width 0.1)
				(type default)
			)
			(layer "F.Fab")
		)
		(fp_line
			(start 0.12065 -0.3048)
			(end 0.67945 -0.3048)
			(stroke
				(width 0.1)
				(type default)
			)
			(layer "F.Fab")
		)
		(fp_line
			(start 0.67945 -0.3048)
			(end 0.67945 0.3048)
			(stroke
				(width 0.1)
				(type default)
			)
			(layer "F.Fab")
		)
		(fp_line
			(start -0.67945 -0.305054)
			(end -0.12065 -0.305054)
			(stroke
				(width 0.1)
				(type default)
			)
			(layer "F.Fab")
		)
		(fp_line
			(start -0.12065 -0.305054)
			(end -0.12065 -0.2794)
			(stroke
				(width 0.1)
				(type default)
			)
			(layer "F.Fab")
		)
		(pad "1" smd circle
			(at -0.40005 0 270)
			(size 0 0)
			(layers "F.Cu" "F.Mask" "F.Paste")
			(net "PVCCFA_EHV_FIVRA_CPU1")
		)
		(pad "2" smd circle
			(at 0.40005 0 270)
			(size 0 0)
			(layers "F.Cu" "F.Mask" "F.Paste")
			(net "GND")
		)
	)
	(footprint ""
		(layer "F.Cu")
		(at 191.295782 -28.267152)
		(property "Reference" "PC2237"
			(at 0 0 0)
			(layer "F.SilkS")
			(hide yes)
			(effects
				(font
					(size 1.27 1.27)
				)
			)
		)
		(property "Value" ""
			(at 0 0 0)
			(layer "F.Fab")
			(effects
				(font
					(size 1.27 1.27)
				)
			)
		)
		(duplicate_pad_numbers_are_jumpers no)
		(fp_line
			(start -0.7874 -0.4064)
			(end 0.7874 -0.4064)
			(stroke
				(width 0.1524)
				(type default)
			)
			(layer "F.SilkS")
		)
		(fp_line
			(start -0.7874 0.4064)
			(end -0.7874 -0.4064)
			(stroke
				(width 0.1524)
				(type default)
			)
			(layer "F.SilkS")
		)
		(fp_line
			(start 0.7874 -0.4064)
			(end 0.7874 0.4064)
			(stroke
				(width 0.1524)
				(type default)
			)
			(layer "F.SilkS")
		)
		(fp_line
			(start 0.7874 0.4064)
			(end -0.7874 0.4064)
			(stroke
				(width 0.1524)
				(type default)
			)
			(layer "F.SilkS")
		)
		(fp_line
			(start -0.67945 -0.305054)
			(end -0.12065 -0.305054)
			(stroke
				(width 0.1)
				(type default)
			)
			(layer "F.Fab")
		)
		(fp_line
			(start -0.67945 0.3048)
			(end -0.67945 -0.305054)
			(stroke
				(width 0.1)
				(type default)
			)
			(layer "F.Fab")
		)
		(fp_line
			(start -0.12065 -0.305054)
			(end -0.12065 -0.2794)
			(stroke
				(width 0.1)
				(type default)
			)
			(layer "F.Fab")
		)
		(fp_line
			(start -0.12065 -0.2794)
			(end 0.12065 -0.2794)
			(stroke
				(width 0.1)
				(type default)
			)
			(layer "F.Fab")
		)
		(fp_line
			(start -0.12065 0.2794)
			(end -0.12065 0.3048)
			(stroke
				(width 0.1)
				(type default)
			)
			(layer "F.Fab")
		)
		(fp_line
			(start -0.12065 0.3048)
			(end -0.67945 0.3048)
			(stroke
				(width 0.1)
				(type default)
			)
			(layer "F.Fab")
		)
		(fp_line
			(start 0.120396 0.2794)
			(end -0.12065 0.2794)
			(stroke
				(width 0.1)
				(type default)
			)
			(layer "F.Fab")
		)
		(fp_line
			(start 0.120396 0.3048)
			(end 0.120396 0.2794)
			(stroke
				(width 0.1)
				(type default)
			)
			(layer "F.Fab")
		)
		(fp_line
			(start 0.12065 -0.3048)
			(end 0.67945 -0.3048)
			(stroke
				(width 0.1)
				(type default)
			)
			(layer "F.Fab")
		)
		(fp_line
			(start 0.12065 -0.2794)
			(end 0.12065 -0.3048)
			(stroke
				(width 0.1)
				(type default)
			)
			(layer "F.Fab")
		)
		(fp_line
			(start 0.67945 -0.3048)
			(end 0.67945 0.3048)
			(stroke
				(width 0.1)
				(type default)
			)
			(layer "F.Fab")
		)
		(fp_line
			(start 0.67945 0.3048)
			(end 0.120396 0.3048)
			(stroke
				(width 0.1)
				(type default)
			)
			(layer "F.Fab")
		)
		(pad "1" smd circle
			(at -0.40005 0)
			(size 0 0)
			(layers "F.Cu" "F.Mask" "F.Paste")
			(net "P12V_SCM_GATE")
		)
		(pad "2" smd circle
			(at 0.40005 0)
			(size 0 0)
			(layers "F.Cu" "F.Mask" "F.Paste")
			(net "GND")
		)
	)
	(footprint ""
		(layer "F.Cu")
		(at 57.75833 -17.623536 90)
		(property "Reference" "C836"
			(at 0 0 90)
			(layer "F.SilkS")
			(hide yes)
			(effects
				(font
					(size 1.27 1.27)
				)
			)
		)
		(property "Value" ""
			(at 0 0 90)
			(layer "F.Fab")
			(effects
				(font
					(size 1.27 1.27)
				)
			)
		)
		(duplicate_pad_numbers_are_jumpers no)
		(fp_line
			(start 0.299974 -0.150114)
			(end 0.299974 0.150114)
			(stroke
				(width 0.1)
				(type default)
			)
			(layer "F.Fab")
		)
		(fp_line
			(start -0.299974 -0.150114)
			(end 0.299974 -0.150114)
			(stroke
				(width 0.1)
				(type default)
			)
			(layer "F.Fab")
		)
		(fp_line
			(start 0.299974 0.150114)
			(end -0.299974 0.150114)
			(stroke
				(width 0.1)
				(type default)
			)
			(layer "F.Fab")
		)
		(fp_line
			(start -0.299974 0.150114)
			(end -0.299974 -0.150114)
			(stroke
				(width 0.1)
				(type default)
			)
			(layer "F.Fab")
		)
		(pad "1" smd rect
			(at -0.2667 0 90)
			(size 0.3048 0.381)
			(layers "F.Cu" "F.Mask" "F.Paste")
			(net "P5E_CPU1_PE1_TX_C_DN<0>")
		)
		(pad "2" smd rect
			(at 0.2667 0 90)
			(size 0.3048 0.381)
			(layers "F.Cu" "F.Mask" "F.Paste")
			(net "P5E_CPU1_PE1_TX_DN<0>")
		)
	)
	(footprint ""
		(layer "F.Cu")
		(at 334.7212 -66.462148 180)
		(property "Reference" "C103"
			(at 0 0 180)
			(layer "F.SilkS")
			(hide yes)
			(effects
				(font
					(size 1.27 1.27)
				)
			)
		)
		(property "Value" ""
			(at 0 0 180)
			(layer "F.Fab")
			(effects
				(font
					(size 1.27 1.27)
				)
			)
		)
		(duplicate_pad_numbers_are_jumpers no)
		(fp_line
			(start 0.7874 0.4064)
			(end -0.7874 0.4064)
			(stroke
				(width 0.1524)
				(type default)
			)
			(layer "F.SilkS")
		)
		(fp_line
			(start 0.7874 -0.4064)
			(end 0.7874 0.4064)
			(stroke
				(width 0.1524)
				(type default)
			)
			(layer "F.SilkS")
		)
		(fp_line
			(start -0.7874 0.4064)
			(end -0.7874 -0.4064)
			(stroke
				(width 0.1524)
				(type default)
			)
			(layer "F.SilkS")
		)
		(fp_line
			(start -0.7874 -0.4064)
			(end 0.7874 -0.4064)
			(stroke
				(width 0.1524)
				(type default)
			)
			(layer "F.SilkS")
		)
		(fp_line
			(start 0.67945 0.3048)
			(end 0.120396 0.3048)
			(stroke
				(width 0.1)
				(type default)
			)
			(layer "F.Fab")
		)
		(fp_line
			(start 0.67945 -0.3048)
			(end 0.67945 0.3048)
			(stroke
				(width 0.1)
				(type default)
			)
			(layer "F.Fab")
		)
		(fp_line
			(start 0.12065 -0.2794)
			(end 0.12065 -0.3048)
			(stroke
				(width 0.1)
				(type default)
			)
			(layer "F.Fab")
		)
		(fp_line
			(start 0.12065 -0.3048)
			(end 0.67945 -0.3048)
			(stroke
				(width 0.1)
				(type default)
			)
			(layer "F.Fab")
		)
		(fp_line
			(start 0.120396 0.3048)
			(end 0.120396 0.2794)
			(stroke
				(width 0.1)
				(type default)
			)
			(layer "F.Fab")
		)
		(fp_line
			(start 0.120396 0.2794)
			(end -0.12065 0.2794)
			(stroke
				(width 0.1)
				(type default)
			)
			(layer "F.Fab")
		)
		(fp_line
			(start -0.12065 0.3048)
			(end -0.67945 0.3048)
			(stroke
				(width 0.1)
				(type default)
			)
			(layer "F.Fab")
		)
		(fp_line
			(start -0.12065 0.2794)
			(end -0.12065 0.3048)
			(stroke
				(width 0.1)
				(type default)
			)
			(layer "F.Fab")
		)
		(fp_line
			(start -0.12065 -0.2794)
			(end 0.12065 -0.2794)
			(stroke
				(width 0.1)
				(type default)
			)
			(layer "F.Fab")
		)
		(fp_line
			(start -0.12065 -0.305054)
			(end -0.12065 -0.2794)
			(stroke
				(width 0.1)
				(type default)
			)
			(layer "F.Fab")
		)
		(fp_line
			(start -0.67945 0.3048)
			(end -0.67945 -0.305054)
			(stroke
				(width 0.1)
				(type default)
			)
			(layer "F.Fab")
		)
		(fp_line
			(start -0.67945 -0.305054)
			(end -0.12065 -0.305054)
			(stroke
				(width 0.1)
				(type default)
			)
			(layer "F.Fab")
		)
		(pad "1" smd circle
			(at -0.40005 0 180)
			(size 0 0)
			(layers "F.Cu" "F.Mask" "F.Paste")
			(net "XTAL_PCH_25M_IN_R")
		)
		(pad "2" smd circle
			(at 0.40005 0 180)
			(size 0 0)
			(layers "F.Cu" "F.Mask" "F.Paste")
			(net "GND")
		)
	)
)
